(kicad_pcb
	(version 20260206)
	(generator "pcbnew")
	(generator_version "10.0")
	(general
		(thickness 1.6)
		(legacy_teardrops no)
	)
	(paper "A4")
	(title_block
		(title "03242023_DA0F0TMBIJ0_F0T_Motherboard_J_brd_V01_OCP.brd")
		(comment 1 "Grand Teton / footprints 5465-5470 of 6105")
	)
	(layers
		(0 "F.Cu" signal "TOP")
		(4 "In1.Cu" signal "GND")
		(6 "In2.Cu" signal "IN1")
		(8 "In3.Cu" signal "GND1")
		(10 "In4.Cu" signal "IN2")
		(12 "In5.Cu" signal "GND2")
		(14 "In6.Cu" signal "IN3")
		(16 "In7.Cu" signal "GND3")
		(18 "In8.Cu" signal "VCC")
		(20 "In9.Cu" signal "VCC1")
		(22 "In10.Cu" signal "GND4")
		(24 "In11.Cu" signal "IN4")
		(26 "In12.Cu" signal "GND5")
		(28 "In13.Cu" signal "IN5")
		(30 "In14.Cu" signal "GND6")
		(32 "In15.Cu" signal "IN6")
		(34 "In16.Cu" signal "GND7")
		(2 "B.Cu" signal "BOTTOM")
		(9 "F.Adhes" user "F.Adhesive")
		(11 "B.Adhes" user "B.Adhesive")
		(13 "F.Paste" user "Package Geometry/Pastemask Top")
		(15 "B.Paste" user "Package Geometry/Pastemask Bottom")
		(5 "F.SilkS" user "Ref Des/Silkscreen Top")
		(7 "B.SilkS" user "Ref Des/Silkscreen Bottom")
		(1 "F.Mask" user "Board Geometry/Soldermask Top")
		(3 "B.Mask" user "Board Geometry/Soldermask Bottom")
		(17 "Dwgs.User" user "User.Drawings")
		(19 "Cmts.User" user "User.Comments")
		(21 "Eco1.User" user "User.Eco1")
		(23 "Eco2.User" user "User.Eco2")
		(25 "Edge.Cuts" user "Board Geometry/Outline")
		(27 "Margin" user)
		(31 "F.CrtYd" user "Package Geometry/Place Bound Top")
		(29 "B.CrtYd" user "Package Geometry/Place Bound Bottom")
		(35 "F.Fab" user "Ref Des/Assembly Top")
		(33 "B.Fab" user "Ref Des/Assembly Bottom")
	)
	(footprint ""
		(layer "B.Cu")
		(at 164.64788 -115.026948 180)
		(property "Reference" "R3505"
			(at 0 0 0)
			(layer "B.SilkS")
			(hide yes)
			(effects
				(font
					(size 1.27 1.27)
				)
				(justify mirror)
			)
		)
		(property "Value" ""
			(at 0 0 0)
			(layer "B.Fab")
			(effects
				(font
					(size 1.27 1.27)
				)
				(justify mirror)
			)
		)
		(duplicate_pad_numbers_are_jumpers no)
		(fp_line
			(start 0.7874 0.4064)
			(end 0.7874 -0.4064)
			(stroke
				(width 0.1524)
				(type default)
			)
			(layer "B.SilkS")
		)
		(fp_line
			(start 0.7874 -0.4064)
			(end -0.7874 -0.4064)
			(stroke
				(width 0.1524)
				(type default)
			)
			(layer "B.SilkS")
		)
		(fp_line
			(start -0.7874 0.4064)
			(end 0.7874 0.4064)
			(stroke
				(width 0.1524)
				(type default)
			)
			(layer "B.SilkS")
		)
		(fp_line
			(start -0.7874 -0.4064)
			(end -0.7874 0.4064)
			(stroke
				(width 0.1524)
				(type default)
			)
			(layer "B.SilkS")
		)
		(fp_line
			(start 0.67945 0.3048)
			(end 0.67945 -0.305054)
			(stroke
				(width 0.1)
				(type default)
			)
			(layer "B.Fab")
		)
		(fp_line
			(start 0.67945 -0.305054)
			(end 0.12065 -0.305054)
			(stroke
				(width 0.1)
				(type default)
			)
			(layer "B.Fab")
		)
		(fp_line
			(start 0.12065 0.3048)
			(end 0.67945 0.3048)
			(stroke
				(width 0.1)
				(type default)
			)
			(layer "B.Fab")
		)
		(fp_line
			(start 0.12065 0.2794)
			(end 0.12065 0.3048)
			(stroke
				(width 0.1)
				(type default)
			)
			(layer "B.Fab")
		)
		(fp_line
			(start 0.12065 -0.2794)
			(end -0.12065 -0.2794)
			(stroke
				(width 0.1)
				(type default)
			)
			(layer "B.Fab")
		)
		(fp_line
			(start 0.12065 -0.305054)
			(end 0.12065 -0.2794)
			(stroke
				(width 0.1)
				(type default)
			)
			(layer "B.Fab")
		)
		(fp_line
			(start -0.120396 0.3048)
			(end -0.120396 0.2794)
			(stroke
				(width 0.1)
				(type default)
			)
			(layer "B.Fab")
		)
		(fp_line
			(start -0.120396 0.2794)
			(end 0.12065 0.2794)
			(stroke
				(width 0.1)
				(type default)
			)
			(layer "B.Fab")
		)
		(fp_line
			(start -0.12065 -0.2794)
			(end -0.12065 -0.3048)
			(stroke
				(width 0.1)
				(type default)
			)
			(layer "B.Fab")
		)
		(fp_line
			(start -0.12065 -0.3048)
			(end -0.67945 -0.3048)
			(stroke
				(width 0.1)
				(type default)
			)
			(layer "B.Fab")
		)
		(fp_line
			(start -0.67945 0.3048)
			(end -0.120396 0.3048)
			(stroke
				(width 0.1)
				(type default)
			)
			(layer "B.Fab")
		)
		(fp_line
			(start -0.67945 -0.3048)
			(end -0.67945 0.3048)
			(stroke
				(width 0.1)
				(type default)
			)
			(layer "B.Fab")
		)
		(pad "1" smd circle
			(at 0.40005 0)
			(size 0 0)
			(layers "B.Cu" "B.Mask" "B.Paste")
			(net "GPU_FPGA_EROT_FATALERR_ISO_N")
		)
		(pad "2" smd circle
			(at -0.40005 0)
			(size 0 0)
			(layers "B.Cu" "B.Mask" "B.Paste")
			(net "GPU_FPGA_EROT_FATALERR_ISO_R_N")
		)
	)
	(footprint ""
		(layer "B.Cu")
		(at 133.069838 -328.298048 -90)
		(property "Reference" "PC522_P1_5"
			(at 0 0 90)
			(layer "B.SilkS")
			(hide yes)
			(effects
				(font
					(size 1.27 1.27)
				)
				(justify mirror)
			)
		)
		(property "Value" ""
			(at 0 0 90)
			(layer "B.Fab")
			(effects
				(font
					(size 1.27 1.27)
				)
				(justify mirror)
			)
		)
		(duplicate_pad_numbers_are_jumpers no)
		(fp_line
			(start -1.524 0.762)
			(end 1.524 0.762)
			(stroke
				(width 0.1524)
				(type default)
			)
			(layer "B.SilkS")
		)
		(fp_line
			(start 1.524 0.762)
			(end 1.524 -0.762)
			(stroke
				(width 0.1524)
				(type default)
			)
			(layer "B.SilkS")
		)
		(fp_line
			(start -1.524 -0.762)
			(end -1.524 0.762)
			(stroke
				(width 0.1524)
				(type default)
			)
			(layer "B.SilkS")
		)
		(fp_line
			(start 1.524 -0.762)
			(end -1.524 -0.762)
			(stroke
				(width 0.1524)
				(type default)
			)
			(layer "B.SilkS")
		)
		(fp_line
			(start -1.1049 0.724916)
			(end -1.1049 -0.724916)
			(stroke
				(width 0.1)
				(type default)
			)
			(layer "B.Fab")
		)
		(fp_line
			(start 1.1049 0.724916)
			(end -1.1049 0.724916)
			(stroke
				(width 0.1)
				(type default)
			)
			(layer "B.Fab")
		)
		(fp_line
			(start -1.1049 -0.724916)
			(end 1.1049 -0.724916)
			(stroke
				(width 0.1)
				(type default)
			)
			(layer "B.Fab")
		)
		(fp_line
			(start 1.1049 -0.724916)
			(end 1.1049 0.724916)
			(stroke
				(width 0.1)
				(type default)
			)
			(layer "B.Fab")
		)
		(pad "1" smd rect
			(at 0.889 0 270)
			(size 1.016 1.27)
			(layers "B.Cu" "B.Mask" "B.Paste")
			(net "PVCCIN_CPU1")
		)
		(pad "2" smd rect
			(at -0.889 0 270)
			(size 1.016 1.27)
			(layers "B.Cu" "B.Mask" "B.Paste")
			(net "GND")
		)
	)
	(footprint ""
		(layer "B.Cu")
		(at 495.90833 -148.094192 -90)
		(property "Reference" "X32"
			(at 3.666236 3.151378 270)
			(unlocked yes)
			(layer "B.SilkS")
			(effects
				(font
					(size 0.7874 0.5842)
					(thickness 0.1524)
				)
				(justify left mirror)
			)
		)
		(property "Value" ""
			(at 0 0 90)
			(layer "B.Fab")
			(effects
				(font
					(size 1.27 1.27)
				)
				(justify mirror)
			)
		)
		(property "Device Type" "TP_TDR_4P_FTS_TH-TP_TDR_4P_DIPA"
			(at -1.30175 1.27 180)
			(unlocked yes)
			(layer "B.Fab")
			(hide yes)
			(effects
				(font
					(size 0.635 0.4064)
					(thickness 0.1524)
				)
				(justify mirror)
			)
		)
		(property "User Part Number" "N_A"
			(at -1.30175 1.27 180)
			(unlocked yes)
			(layer "Cmts.User")
			(hide yes)
			(effects
				(font
					(size 0.635 0.4064)
					(thickness 0.1524)
				)
				(justify mirror)
			)
		)
		(duplicate_pad_numbers_are_jumpers no)
		(fp_line
			(start -2.54 3.81)
			(end -2.54 3.6703)
			(stroke
				(width 0.1524)
				(type default)
			)
			(layer "B.SilkS")
		)
		(fp_line
			(start 0 3.81)
			(end -2.54 3.81)
			(stroke
				(width 0.1524)
				(type default)
			)
			(layer "B.SilkS")
		)
		(fp_line
			(start 0 3.175)
			(end 0 3.81)
			(stroke
				(width 0.1524)
				(type default)
			)
			(layer "B.SilkS")
		)
		(fp_line
			(start -2.54 1.4097)
			(end -2.54 1.1303)
			(stroke
				(width 0.1524)
				(type default)
			)
			(layer "B.SilkS")
		)
		(fp_line
			(start 0 0.635)
			(end 0 1.905)
			(stroke
				(width 0.1524)
				(type default)
			)
			(layer "B.SilkS")
		)
		(fp_line
			(start -2.54 -1.1303)
			(end -2.54 -1.27)
			(stroke
				(width 0.1524)
				(type default)
			)
			(layer "B.SilkS")
		)
		(fp_line
			(start -2.54 -1.27)
			(end 0 -1.27)
			(stroke
				(width 0.1524)
				(type default)
			)
			(layer "B.SilkS")
		)
		(fp_line
			(start 0 -1.27)
			(end 0 -0.635)
			(stroke
				(width 0.1524)
				(type default)
			)
			(layer "B.SilkS")
		)
		(fp_poly
			(pts
				(xy 2.981706 -0.88646) (xy 2.981706 0.63754) (xy 1.457706 -0.12446)
			)
			(stroke
				(width 0)
				(type default)
			)
			(fill yes)
			(layer "B.SilkS")
		)
		(fp_line
			(start -2.54 3.81)
			(end -2.54 -1.27)
			(stroke
				(width 0.1)
				(type default)
			)
			(layer "B.Fab")
		)
		(fp_line
			(start 0 3.81)
			(end -2.54 3.81)
			(stroke
				(width 0.1)
				(type default)
			)
			(layer "B.Fab")
		)
		(fp_line
			(start -2.54 -1.27)
			(end 0 -1.27)
			(stroke
				(width 0.1)
				(type default)
			)
			(layer "B.Fab")
		)
		(fp_line
			(start 0 -1.27)
			(end 0 3.81)
			(stroke
				(width 0.1)
				(type default)
			)
			(layer "B.Fab")
		)
		(fp_poly
			(pts
				(xy 0.761746 0) (xy 2.285746 -0.762) (xy 2.285746 0.762)
			)
			(stroke
				(width 0)
				(type default)
			)
			(fill yes)
			(layer "B.Fab")
		)
		(pad "1" thru_hole circle
			(at 0 0 90)
			(size 1.0033 1.0033)
			(drill 0.249936)
			(layers "*.Cu" "*.Mask")
			(remove_unused_layers no)
			(net "TDR_DIFF_100_IN6_DN")
			(clearance 0.10795)
			(padstack
				(mode front_inner_back)
				(layer "Inner"
					(shape circle)
					(size 0.8001 0.8001)
					(clearance 0.1524)
				)
				(layer "B.Cu"
					(shape circle)
					(size 1.0033 1.0033)
					(thermal_gap 0.10795)
					(clearance 0.10795)
				)
			)
		)
		(pad "2" thru_hole circle
			(at -2.54 0 90)
			(size 1.9939 1.9939)
			(drill 0.249936)
			(layers "*.Cu" "*.Mask")
			(remove_unused_layers no)
			(net "T1_GND")
			(clearance 0.10795)
			(padstack
				(mode front_inner_back)
				(layer "Inner"
					(shape circle)
					(size 0.8001 0.8001)
					(clearance 0.1524)
				)
				(layer "B.Cu"
					(shape circle)
					(size 1.9939 1.9939)
					(thermal_gap 0.10795)
					(clearance 0.10795)
				)
			)
		)
		(pad "3" thru_hole circle
			(at -2.54 2.54 90)
			(size 1.9939 1.9939)
			(drill 0.249936)
			(layers "*.Cu" "*.Mask")
			(remove_unused_layers no)
			(net "T1_GND")
			(clearance 0.10795)
			(padstack
				(mode front_inner_back)
				(layer "Inner"
					(shape circle)
					(size 0.8001 0.8001)
					(clearance 0.1524)
				)
				(layer "B.Cu"
					(shape circle)
					(size 1.9939 1.9939)
					(thermal_gap 0.10795)
					(clearance 0.10795)
				)
			)
		)
		(pad "4" thru_hole circle
			(at 0 2.54 90)
			(size 1.0033 1.0033)
			(drill 0.249936)
			(layers "*.Cu" "*.Mask")
			(remove_unused_layers no)
			(net "TDR_DIFF_100_IN6_DP")
			(clearance 0.10795)
			(padstack
				(mode front_inner_back)
				(layer "Inner"
					(shape circle)
					(size 0.8001 0.8001)
					(clearance 0.1524)
				)
				(layer "B.Cu"
					(shape circle)
					(size 1.0033 1.0033)
					(thermal_gap 0.10795)
					(clearance 0.10795)
				)
			)
		)
	)
	(footprint ""
		(layer "B.Cu")
		(at 261.655814 -100.91547 180)
		(property "Reference" "C1310"
			(at 0 0 0)
			(layer "B.SilkS")
			(hide yes)
			(effects
				(font
					(size 1.27 1.27)
				)
				(justify mirror)
			)
		)
		(property "Value" ""
			(at 0 0 0)
			(layer "B.Fab")
			(effects
				(font
					(size 1.27 1.27)
				)
				(justify mirror)
			)
		)
		(duplicate_pad_numbers_are_jumpers no)
		(fp_line
			(start 1.2954 0.5842)
			(end 1.2954 -0.5842)
			(stroke
				(width 0.1524)
				(type default)
			)
			(layer "B.SilkS")
		)
		(fp_line
			(start 1.2954 -0.5842)
			(end -1.2954 -0.5842)
			(stroke
				(width 0.1524)
				(type default)
			)
			(layer "B.SilkS")
		)
		(fp_line
			(start 0 -0.5842)
			(end 0 0.5842)
			(stroke
				(width 0.1524)
				(type default)
			)
			(layer "B.SilkS")
		)
		(fp_line
			(start -1.2954 0.5842)
			(end 1.2954 0.5842)
			(stroke
				(width 0.1524)
				(type default)
			)
			(layer "B.SilkS")
		)
		(fp_line
			(start -1.2954 -0.5842)
			(end -1.2954 0.5842)
			(stroke
				(width 0.1524)
				(type default)
			)
			(layer "B.SilkS")
		)
		(fp_line
			(start 1.1938 0.4064)
			(end 1.1938 -0.4064)
			(stroke
				(width 0.1)
				(type default)
			)
			(layer "B.Fab")
		)
		(fp_line
			(start 1.1938 -0.4064)
			(end 0.8636 -0.4064)
			(stroke
				(width 0.1)
				(type default)
			)
			(layer "B.Fab")
		)
		(fp_line
			(start 0.8636 0.4572)
			(end 0.8636 0.4064)
			(stroke
				(width 0.1)
				(type default)
			)
			(layer "B.Fab")
		)
		(fp_line
			(start 0.8636 0.4064)
			(end 1.1938 0.4064)
			(stroke
				(width 0.1)
				(type default)
			)
			(layer "B.Fab")
		)
		(fp_line
			(start 0.8636 -0.4064)
			(end 0.8636 -0.4572)
			(stroke
				(width 0.1)
				(type default)
			)
			(layer "B.Fab")
		)
		(fp_line
			(start 0.8636 -0.4572)
			(end -0.8636 -0.4572)
			(stroke
				(width 0.1)
				(type default)
			)
			(layer "B.Fab")
		)
		(fp_line
			(start -0.8636 0.4572)
			(end 0.8636 0.4572)
			(stroke
				(width 0.1)
				(type default)
			)
			(layer "B.Fab")
		)
		(fp_line
			(start -0.8636 0.4064)
			(end -0.8636 0.4572)
			(stroke
				(width 0.1)
				(type default)
			)
			(layer "B.Fab")
		)
		(fp_line
			(start -0.8636 -0.4064)
			(end -1.1938 -0.4064)
			(stroke
				(width 0.1)
				(type default)
			)
			(layer "B.Fab")
		)
		(fp_line
			(start -0.8636 -0.4572)
			(end -0.8636 -0.4064)
			(stroke
				(width 0.1)
				(type default)
			)
			(layer "B.Fab")
		)
		(fp_line
			(start -1.1938 0.4064)
			(end -0.8636 0.4064)
			(stroke
				(width 0.1)
				(type default)
			)
			(layer "B.Fab")
		)
		(fp_line
			(start -1.1938 -0.4064)
			(end -1.1938 0.4064)
			(stroke
				(width 0.1)
				(type default)
			)
			(layer "B.Fab")
		)
		(pad "1" smd rect
			(at 0.7366 0 90)
			(size 0.7112 0.8128)
			(layers "B.Cu" "B.Mask" "B.Paste")
			(net "P3V3_AUX_CLK_GEN_VDDMXCK_CK440")
		)
		(pad "2" smd rect
			(at -0.7366 0 90)
			(size 0.7112 0.8128)
			(layers "B.Cu" "B.Mask" "B.Paste")
			(net "GND")
		)
	)
	(footprint ""
		(layer "B.Cu")
		(at 414.255712 -193.08953 -90)
		(property "Reference" "R320"
			(at 0 0 90)
			(layer "B.SilkS")
			(hide yes)
			(effects
				(font
					(size 1.27 1.27)
				)
				(justify mirror)
			)
		)
		(property "Value" ""
			(at 0 0 90)
			(layer "B.Fab")
			(effects
				(font
					(size 1.27 1.27)
				)
				(justify mirror)
			)
		)
		(duplicate_pad_numbers_are_jumpers no)
		(fp_line
			(start -0.7874 0.4064)
			(end 0.7874 0.4064)
			(stroke
				(width 0.1524)
				(type default)
			)
			(layer "B.SilkS")
		)
		(fp_line
			(start 0.7874 0.4064)
			(end 0.7874 -0.4064)
			(stroke
				(width 0.1524)
				(type default)
			)
			(layer "B.SilkS")
		)
		(fp_line
			(start -0.7874 -0.4064)
			(end -0.7874 0.4064)
			(stroke
				(width 0.1524)
				(type default)
			)
			(layer "B.SilkS")
		)
		(fp_line
			(start 0.7874 -0.4064)
			(end -0.7874 -0.4064)
			(stroke
				(width 0.1524)
				(type default)
			)
			(layer "B.SilkS")
		)
		(fp_line
			(start -0.67945 0.3048)
			(end -0.120396 0.3048)
			(stroke
				(width 0.1)
				(type default)
			)
			(layer "B.Fab")
		)
		(fp_line
			(start -0.120396 0.3048)
			(end -0.120396 0.2794)
			(stroke
				(width 0.1)
				(type default)
			)
			(layer "B.Fab")
		)
		(fp_line
			(start 0.12065 0.3048)
			(end 0.67945 0.3048)
			(stroke
				(width 0.1)
				(type default)
			)
			(layer "B.Fab")
		)
		(fp_line
			(start 0.67945 0.3048)
			(end 0.67945 -0.305054)
			(stroke
				(width 0.1)
				(type default)
			)
			(layer "B.Fab")
		)
		(fp_line
			(start -0.120396 0.2794)
			(end 0.12065 0.2794)
			(stroke
				(width 0.1)
				(type default)
			)
			(layer "B.Fab")
		)
		(fp_line
			(start 0.12065 0.2794)
			(end 0.12065 0.3048)
			(stroke
				(width 0.1)
				(type default)
			)
			(layer "B.Fab")
		)
		(fp_line
			(start -0.12065 -0.2794)
			(end -0.12065 -0.3048)
			(stroke
				(width 0.1)
				(type default)
			)
			(layer "B.Fab")
		)
		(fp_line
			(start 0.12065 -0.2794)
			(end -0.12065 -0.2794)
			(stroke
				(width 0.1)
				(type default)
			)
			(layer "B.Fab")
		)
		(fp_line
			(start -0.67945 -0.3048)
			(end -0.67945 0.3048)
			(stroke
				(width 0.1)
				(type default)
			)
			(layer "B.Fab")
		)
		(fp_line
			(start -0.12065 -0.3048)
			(end -0.67945 -0.3048)
			(stroke
				(width 0.1)
				(type default)
			)
			(layer "B.Fab")
		)
		(fp_line
			(start 0.12065 -0.305054)
			(end 0.12065 -0.2794)
			(stroke
				(width 0.1)
				(type default)
			)
			(layer "B.Fab")
		)
		(fp_line
			(start 0.67945 -0.305054)
			(end 0.12065 -0.305054)
			(stroke
				(width 0.1)
				(type default)
			)
			(layer "B.Fab")
		)
		(pad "1" smd circle
			(at 0.40005 0 90)
			(size 0 0)
			(layers "B.Cu" "B.Mask" "B.Paste")
			(net "P3V3_AUX")
		)
		(pad "2" smd circle
			(at -0.40005 0 90)
			(size 0 0)
			(layers "B.Cu" "B.Mask" "B.Paste")
			(net "PU_S3M_CPU0_CPLD_CONFD")
		)
	)
	(footprint ""
		(layer "B.Cu")
		(at 213.525354 -314.550044 90)
		(property "Reference" "R2505"
			(at 0 0 90)
			(layer "B.SilkS")
			(hide yes)
			(effects
				(font
					(size 1.27 1.27)
				)
				(justify mirror)
			)
		)
		(property "Value" ""
			(at 0 0 90)
			(layer "B.Fab")
			(effects
				(font
					(size 1.27 1.27)
				)
				(justify mirror)
			)
		)
		(duplicate_pad_numbers_are_jumpers no)
		(fp_line
			(start 0.7874 -0.4064)
			(end -0.7874 -0.4064)
			(stroke
				(width 0.1524)
				(type default)
			)
			(layer "B.SilkS")
		)
		(fp_line
			(start -0.7874 -0.4064)
			(end -0.7874 0.4064)
			(stroke
				(width 0.1524)
				(type default)
			)
			(layer "B.SilkS")
		)
		(fp_line
			(start 0.7874 0.4064)
			(end 0.7874 -0.4064)
			(stroke
				(width 0.1524)
				(type default)
			)
			(layer "B.SilkS")
		)
		(fp_line
			(start -0.7874 0.4064)
			(end 0.7874 0.4064)
			(stroke
				(width 0.1524)
				(type default)
			)
			(layer "B.SilkS")
		)
		(fp_line
			(start 0.67945 -0.305054)
			(end 0.12065 -0.305054)
			(stroke
				(width 0.1)
				(type default)
			)
			(layer "B.Fab")
		)
		(fp_line
			(start 0.12065 -0.305054)
			(end 0.12065 -0.2794)
			(stroke
				(width 0.1)
				(type default)
			)
			(layer "B.Fab")
		)
		(fp_line
			(start -0.12065 -0.3048)
			(end -0.67945 -0.3048)
			(stroke
				(width 0.1)
				(type default)
			)
			(layer "B.Fab")
		)
		(fp_line
			(start -0.67945 -0.3048)
			(end -0.67945 0.3048)
			(stroke
				(width 0.1)
				(type default)
			)
			(layer "B.Fab")
		)
		(fp_line
			(start 0.12065 -0.2794)
			(end -0.12065 -0.2794)
			(stroke
				(width 0.1)
				(type default)
			)
			(layer "B.Fab")
		)
		(fp_line
			(start -0.12065 -0.2794)
			(end -0.12065 -0.3048)
			(stroke
				(width 0.1)
				(type default)
			)
			(layer "B.Fab")
		)
		(fp_line
			(start 0.12065 0.2794)
			(end 0.12065 0.3048)
			(stroke
				(width 0.1)
				(type default)
			)
			(layer "B.Fab")
		)
		(fp_line
			(start -0.120396 0.2794)
			(end 0.12065 0.2794)
			(stroke
				(width 0.1)
				(type default)
			)
			(layer "B.Fab")
		)
		(fp_line
			(start 0.67945 0.3048)
			(end 0.67945 -0.305054)
			(stroke
				(width 0.1)
				(type default)
			)
			(layer "B.Fab")
		)
		(fp_line
			(start 0.12065 0.3048)
			(end 0.67945 0.3048)
			(stroke
				(width 0.1)
				(type default)
			)
			(layer "B.Fab")
		)
		(fp_line
			(start -0.120396 0.3048)
			(end -0.120396 0.2794)
			(stroke
				(width 0.1)
				(type default)
			)
			(layer "B.Fab")
		)
		(fp_line
			(start -0.67945 0.3048)
			(end -0.120396 0.3048)
			(stroke
				(width 0.1)
				(type default)
			)
			(layer "B.Fab")
		)
		(pad "1" smd circle
			(at 0.40005 0 270)
			(size 0 0)
			(layers "B.Cu" "B.Mask" "B.Paste")
			(net "PWRGD_FAIL_CPU1_GH_R1")
		)
		(pad "2" smd circle
			(at -0.40005 0 270)
			(size 0 0)
			(layers "B.Cu" "B.Mask" "B.Paste")
			(net "PWRGD_FAIL_CPU1_GH_R")
		)
	)
)
